(kicad_pcb
	(version 20260206)
	(generator "pcbnew")
	(generator_version "10.0")
	(general
		(thickness 1.6)
		(legacy_teardrops no)
	)
	(paper "A4")
	(title_block
		(title "panther-plus-userver — 13130-1b_20150205.brd")
		(comment 1 "Honey Badger (Wiwynn) / footprint 406 of 1509 (DIMM2), pads 107-113 of 210")
	)
	(layers
		(0 "F.Cu" signal "TOP")
		(4 "In1.Cu" signal "L2")
		(6 "In2.Cu" signal "L3")
		(8 "In3.Cu" signal "L4")
		(10 "In4.Cu" signal "L5")
		(12 "In5.Cu" signal "L6")
		(14 "In6.Cu" signal "L7")
		(16 "In7.Cu" signal "L8")
		(18 "In8.Cu" signal "L9")
		(20 "In9.Cu" signal "L10")
		(22 "In10.Cu" signal "L11")
		(2 "B.Cu" signal "BOTTOM")
		(9 "F.Adhes" user "F.Adhesive")
		(11 "B.Adhes" user "B.Adhesive")
		(13 "F.Paste" user "Package Geometry/Pastemask Top")
		(15 "B.Paste" user "Package Geometry/Pastemask Bottom")
		(5 "F.SilkS" user "Ref Des/Silkscreen Top")
		(7 "B.SilkS" user "Ref Des/Silkscreen Bottom")
		(1 "F.Mask" user "Board Geometry/Soldermask Top")
		(3 "B.Mask" user "Board Geometry/Soldermask Bottom")
		(17 "Dwgs.User" user "User.Drawings")
		(19 "Cmts.User" user "User.Comments")
		(21 "Eco1.User" user "User.Eco1")
		(23 "Eco2.User" user "User.Eco2")
		(25 "Edge.Cuts" user "Board Geometry/Outline")
		(27 "Margin" user)
		(31 "F.CrtYd" user "Package Geometry/Place Bound Top")
		(29 "B.CrtYd" user "Package Geometry/Place Bound Bottom")
		(35 "F.Fab" user "Ref Des/Assembly Top")
		(33 "B.Fab" user "Ref Des/Assembly Bottom")
	)
	(footprint ""
		(layer "F.Cu")
		(at 158.500064 -66.699892 180)
		(property "Reference" "DIMM2"
			(at 0 0 180)
			(layer "F.SilkS")
			(hide yes)
			(effects
				(font
					(size 1.27 1.27)
				)
			)
		)
		(property "Value" "DDR3-204P-174-COLAY-1-GP"
			(at -40.682164 -17.468088 180)
			(unlocked yes)
			(layer "F.Fab")
			(hide yes)
			(effects
				(font
					(size 1.016 1.016)
					(thickness 0.1524)
				)
			)
		)
		(property "Device Type" "AS0A626-H8SN-7H-COLAY-1"
			(at -40.682164 -18.992088 180)
			(unlocked yes)
			(layer "F.Fab")
			(hide yes)
			(effects
				(font
					(size 1.016 1.016)
					(thickness 0.1524)
				)
			)
		)
		(duplicate_pad_numbers_are_jumpers no)
		(pad "105" smd custom
			(at 1.949958 4.106672 180)
			(size 0.1143 0.1143)
			(layers "F.Cu" "F.Mask" "F.Paste")
			(net "M_A_MA1")
			(options
				(clearance outline)
				(anchor circle)
			)
			(primitives
				(gr_poly
					(pts
						(xy 0 0.9017) (xy -0.03175 0.89916) (xy -0.0635 0.889) (xy -0.09144 0.87376) (xy -0.11684 0.85344)
						(xy -0.13716 0.82804) (xy -0.1524 0.8001) (xy -0.16256 0.76835) (xy -0.1651 0.7366) (xy -0.1651 -0.13462)
						(xy -0.17272 -0.14224) (xy -0.19812 -0.1778) (xy -0.2032 -0.18796) (xy -0.20701 -0.19685) (xy -0.21209 -0.20701)
						(xy -0.2159 -0.21717) (xy -0.21844 -0.22733) (xy -0.22225 -0.23876) (xy -0.22352 -0.24892) (xy -0.22606 -0.25908)
						(xy -0.22733 -0.27051) (xy -0.22733 -0.28067) (xy -0.2286 -0.2921) (xy -0.22733 -0.30353) (xy -0.22733 -0.31369)
						(xy -0.22606 -0.32512) (xy -0.22352 -0.33528) (xy -0.22225 -0.34544) (xy -0.21844 -0.35687) (xy -0.2159 -0.36703)
						(xy -0.21209 -0.37719) (xy -0.20701 -0.38735) (xy -0.2032 -0.39624) (xy -0.19812 -0.4064) (xy -0.17272 -0.44196)
						(xy -0.1651 -0.44958) (xy -0.1651 -0.7366) (xy -0.16256 -0.76835) (xy -0.1524 -0.8001) (xy -0.13716 -0.82804)
						(xy -0.11684 -0.85344) (xy -0.09144 -0.87376) (xy -0.0635 -0.889) (xy -0.03175 -0.89916) (xy 0 -0.9017)
						(xy 0.03175 -0.89916) (xy 0.0635 -0.889) (xy 0.09144 -0.87376) (xy 0.11684 -0.85344) (xy 0.13716 -0.82804)
						(xy 0.1524 -0.8001) (xy 0.16256 -0.76835) (xy 0.1651 -0.7366) (xy 0.1651 -0.44958) (xy 0.17272 -0.44196)
						(xy 0.19812 -0.4064) (xy 0.2032 -0.39624) (xy 0.20701 -0.38735) (xy 0.21209 -0.37719) (xy 0.2159 -0.36703)
						(xy 0.21844 -0.35687) (xy 0.22225 -0.34544) (xy 0.22352 -0.33528) (xy 0.22606 -0.32512) (xy 0.22733 -0.31369)
						(xy 0.22733 -0.30353) (xy 0.2286 -0.2921) (xy 0.22733 -0.28067) (xy 0.22733 -0.27051) (xy 0.22606 -0.25908)
						(xy 0.22352 -0.24892) (xy 0.22225 -0.23876) (xy 0.21844 -0.22733) (xy 0.2159 -0.21717) (xy 0.21209 -0.20701)
						(xy 0.20701 -0.19685) (xy 0.2032 -0.18796) (xy 0.19812 -0.1778) (xy 0.17272 -0.14224) (xy 0.1651 -0.13462)
						(xy 0.1651 0.7366) (xy 0.16256 0.76835) (xy 0.1524 0.8001) (xy 0.13716 0.82804) (xy 0.11684 0.85344)
						(xy 0.09144 0.87376) (xy 0.0635 0.889) (xy 0.03175 0.89916)
					)
					(width 0)
					(fill yes)
				)
			)
		)
		(pad "106" smd custom
			(at 2.249932 -4.106672 180)
			(size 0.1143 0.1143)
			(layers "F.Cu" "F.Mask" "F.Paste")
			(net "M_A_MA2")
			(options
				(clearance outline)
				(anchor circle)
			)
			(primitives
				(gr_poly
					(pts
						(xy 0 0.9017) (xy -0.03175 0.89916) (xy -0.0635 0.889) (xy -0.09144 0.87376) (xy -0.11684 0.85344)
						(xy -0.13716 0.82804) (xy -0.1524 0.8001) (xy -0.16256 0.76835) (xy -0.1651 0.7366) (xy -0.1651 0.44958)
						(xy -0.17272 0.44196) (xy -0.19812 0.4064) (xy -0.2032 0.39624) (xy -0.20701 0.38735) (xy -0.21209 0.37719)
						(xy -0.2159 0.36703) (xy -0.21844 0.35687) (xy -0.22225 0.34544) (xy -0.22352 0.33528) (xy -0.22606 0.32512)
						(xy -0.22733 0.31369) (xy -0.22733 0.30353) (xy -0.2286 0.2921) (xy -0.22733 0.28067) (xy -0.22733 0.27051)
						(xy -0.22606 0.25908) (xy -0.22352 0.24892) (xy -0.22225 0.23876) (xy -0.21844 0.22733) (xy -0.2159 0.21717)
						(xy -0.21209 0.20701) (xy -0.20701 0.19685) (xy -0.2032 0.18796) (xy -0.19812 0.1778) (xy -0.17272 0.14224)
						(xy -0.1651 0.13462) (xy -0.1651 -0.7366) (xy -0.16256 -0.76835) (xy -0.1524 -0.8001) (xy -0.13716 -0.82804)
						(xy -0.11684 -0.85344) (xy -0.09144 -0.87376) (xy -0.0635 -0.889) (xy -0.03175 -0.89916) (xy 0 -0.9017)
						(xy 0.03175 -0.89916) (xy 0.0635 -0.889) (xy 0.09144 -0.87376) (xy 0.11684 -0.85344) (xy 0.13716 -0.82804)
						(xy 0.1524 -0.8001) (xy 0.16256 -0.76835) (xy 0.1651 -0.7366) (xy 0.1651 0.13462) (xy 0.17272 0.14224)
						(xy 0.19812 0.1778) (xy 0.2032 0.18796) (xy 0.20701 0.19685) (xy 0.21209 0.20701) (xy 0.2159 0.21717)
						(xy 0.21844 0.22733) (xy 0.22225 0.23876) (xy 0.22352 0.24892) (xy 0.22606 0.25908) (xy 0.22733 0.27051)
						(xy 0.22733 0.28067) (xy 0.2286 0.2921) (xy 0.22733 0.30353) (xy 0.22733 0.31369) (xy 0.22606 0.32512)
						(xy 0.22352 0.33528) (xy 0.22225 0.34544) (xy 0.21844 0.35687) (xy 0.2159 0.36703) (xy 0.21209 0.37719)
						(xy 0.20701 0.38735) (xy 0.2032 0.39624) (xy 0.19812 0.4064) (xy 0.17272 0.44196) (xy 0.1651 0.44958)
						(xy 0.1651 0.7366) (xy 0.16256 0.76835) (xy 0.1524 0.8001) (xy 0.13716 0.82804) (xy 0.11684 0.85344)
						(xy 0.09144 0.87376) (xy 0.0635 0.889) (xy 0.03175 0.89916)
					)
					(width 0)
					(fill yes)
				)
			)
		)
		(pad "107" smd custom
			(at 2.549906 4.106672 180)
			(size 0.1143 0.1143)
			(layers "F.Cu" "F.Mask" "F.Paste")
			(net "M_A_MA0")
			(options
				(clearance outline)
				(anchor circle)
			)
			(primitives
				(gr_poly
					(pts
						(xy 0 0.9017) (xy -0.03175 0.89916) (xy -0.0635 0.889) (xy -0.09144 0.87376) (xy -0.11684 0.85344)
						(xy -0.13716 0.82804) (xy -0.1524 0.8001) (xy -0.16256 0.76835) (xy -0.1651 0.7366) (xy -0.1651 0.11938)
						(xy -0.17272 0.11176) (xy -0.19812 0.0762) (xy -0.2032 0.06604) (xy -0.20701 0.05715) (xy -0.21209 0.04699)
						(xy -0.2159 0.03683) (xy -0.21844 0.02667) (xy -0.22225 0.01524) (xy -0.22352 0.00508) (xy -0.22606 -0.00508)
						(xy -0.22733 -0.01651) (xy -0.22733 -0.02667) (xy -0.2286 -0.0381) (xy -0.22733 -0.04953) (xy -0.22733 -0.05969)
						(xy -0.22606 -0.07112) (xy -0.22352 -0.08128) (xy -0.22225 -0.09144) (xy -0.21844 -0.10287) (xy -0.2159 -0.11303)
						(xy -0.21209 -0.12319) (xy -0.20701 -0.13335) (xy -0.2032 -0.14224) (xy -0.19812 -0.1524) (xy -0.17272 -0.18796)
						(xy -0.1651 -0.19558) (xy -0.1651 -0.7366) (xy -0.16256 -0.76835) (xy -0.1524 -0.8001) (xy -0.13716 -0.82804)
						(xy -0.11684 -0.85344) (xy -0.09144 -0.87376) (xy -0.0635 -0.889) (xy -0.03175 -0.89916) (xy 0 -0.9017)
						(xy 0.03175 -0.89916) (xy 0.0635 -0.889) (xy 0.09144 -0.87376) (xy 0.11684 -0.85344) (xy 0.13716 -0.82804)
						(xy 0.1524 -0.8001) (xy 0.16256 -0.76835) (xy 0.1651 -0.7366) (xy 0.1651 -0.19685) (xy 0.17272 -0.18923)
						(xy 0.17907 -0.18034) (xy 0.18669 -0.17145) (xy 0.19177 -0.16256) (xy 0.19812 -0.15367) (xy 0.20828 -0.13335)
						(xy 0.21971 -0.10287) (xy 0.22225 -0.09271) (xy 0.22479 -0.08128) (xy 0.22606 -0.07112) (xy 0.2286 -0.05969)
						(xy 0.2286 -0.01651) (xy 0.22606 -0.00508) (xy 0.22479 0.00508) (xy 0.22225 0.01651) (xy 0.21971 0.02667)
						(xy 0.20828 0.05715) (xy 0.19812 0.07747) (xy 0.19177 0.08636) (xy 0.18669 0.09525) (xy 0.17907 0.10414)
						(xy 0.17272 0.11303) (xy 0.1651 0.12065) (xy 0.1651 0.7366) (xy 0.16256 0.76835) (xy 0.1524 0.8001)
						(xy 0.13716 0.82804) (xy 0.11684 0.85344) (xy 0.09144 0.87376) (xy 0.0635 0.889) (xy 0.03175 0.89916)
					)
					(width 0)
					(fill yes)
				)
			)
		)
		(pad "108" smd custom
			(at 2.84988 -4.106672 180)
			(size 0.1143 0.1143)
			(layers "F.Cu" "F.Mask" "F.Paste")
			(net "M_A_BS1")
			(options
				(clearance outline)
				(anchor circle)
			)
			(primitives
				(gr_poly
					(pts
						(xy 0 0.9017) (xy -0.03175 0.89916) (xy -0.0635 0.889) (xy -0.09144 0.87376) (xy -0.11684 0.85344)
						(xy -0.13716 0.82804) (xy -0.1524 0.8001) (xy -0.16256 0.76835) (xy -0.1651 0.7366) (xy -0.1651 0.19685)
						(xy -0.17272 0.18923) (xy -0.17907 0.18034) (xy -0.18669 0.17145) (xy -0.19177 0.16256) (xy -0.19812 0.15367)
						(xy -0.20828 0.13335) (xy -0.21971 0.10287) (xy -0.22225 0.09271) (xy -0.22479 0.08128) (xy -0.22606 0.07112)
						(xy -0.2286 0.05969) (xy -0.2286 0.01651) (xy -0.22606 0.00508) (xy -0.22479 -0.00508) (xy -0.22225 -0.01651)
						(xy -0.21971 -0.02667) (xy -0.20828 -0.05715) (xy -0.19812 -0.07747) (xy -0.19177 -0.08636) (xy -0.18669 -0.09525)
						(xy -0.17907 -0.10414) (xy -0.17272 -0.11303) (xy -0.1651 -0.12065) (xy -0.1651 -0.7366) (xy -0.16256 -0.76835)
						(xy -0.1524 -0.8001) (xy -0.13716 -0.82804) (xy -0.11684 -0.85344) (xy -0.09144 -0.87376) (xy -0.0635 -0.889)
						(xy -0.03175 -0.89916) (xy 0 -0.9017) (xy 0.03175 -0.89916) (xy 0.0635 -0.889) (xy 0.09144 -0.87376)
						(xy 0.11684 -0.85344) (xy 0.13716 -0.82804) (xy 0.1524 -0.8001) (xy 0.16256 -0.76835) (xy 0.1651 -0.7366)
						(xy 0.1651 -0.11938) (xy 0.17272 -0.11176) (xy 0.19812 -0.0762) (xy 0.2032 -0.06604) (xy 0.20701 -0.05715)
						(xy 0.21209 -0.04699) (xy 0.2159 -0.03683) (xy 0.21844 -0.02667) (xy 0.22225 -0.01524) (xy 0.22352 -0.00508)
						(xy 0.22606 0.00508) (xy 0.22733 0.01651) (xy 0.22733 0.02667) (xy 0.2286 0.0381) (xy 0.22733 0.04953)
						(xy 0.22733 0.05969) (xy 0.22606 0.07112) (xy 0.22352 0.08128) (xy 0.22225 0.09144) (xy 0.21844 0.10287)
						(xy 0.2159 0.11303) (xy 0.21209 0.12319) (xy 0.20701 0.13335) (xy 0.2032 0.14224) (xy 0.19812 0.1524)
						(xy 0.17272 0.18796) (xy 0.1651 0.19558) (xy 0.1651 0.7366) (xy 0.16256 0.76835) (xy 0.1524 0.8001)
						(xy 0.13716 0.82804) (xy 0.11684 0.85344) (xy 0.09144 0.87376) (xy 0.0635 0.889) (xy 0.03175 0.89916)
					)
					(width 0)
					(fill yes)
				)
			)
		)
		(pad "109" smd custom
			(at 3.150108 4.106672 180)
			(size 0.1143 0.1143)
			(layers "F.Cu" "F.Mask" "F.Paste")
			(net "PV_VDDR")
			(options
				(clearance outline)
				(anchor circle)
			)
			(primitives
				(gr_poly
					(pts
						(xy 0 0.9017) (xy -0.03175 0.89916) (xy -0.0635 0.889) (xy -0.09144 0.87376) (xy -0.11684 0.85344)
						(xy -0.13716 0.82804) (xy -0.1524 0.8001) (xy -0.16256 0.76835) (xy -0.1651 0.7366) (xy -0.1651 -0.13462)
						(xy -0.17272 -0.14224) (xy -0.19812 -0.1778) (xy -0.2032 -0.18796) (xy -0.20701 -0.19685) (xy -0.21209 -0.20701)
						(xy -0.2159 -0.21717) (xy -0.21844 -0.22733) (xy -0.22225 -0.23876) (xy -0.22352 -0.24892) (xy -0.22606 -0.25908)
						(xy -0.22733 -0.27051) (xy -0.22733 -0.28067) (xy -0.2286 -0.2921) (xy -0.22733 -0.30353) (xy -0.22733 -0.31369)
						(xy -0.22606 -0.32512) (xy -0.22352 -0.33528) (xy -0.22225 -0.34544) (xy -0.21844 -0.35687) (xy -0.2159 -0.36703)
						(xy -0.21209 -0.37719) (xy -0.20701 -0.38735) (xy -0.2032 -0.39624) (xy -0.19812 -0.4064) (xy -0.17272 -0.44196)
						(xy -0.1651 -0.44958) (xy -0.1651 -0.7366) (xy -0.16256 -0.76835) (xy -0.1524 -0.8001) (xy -0.13716 -0.82804)
						(xy -0.11684 -0.85344) (xy -0.09144 -0.87376) (xy -0.0635 -0.889) (xy -0.03175 -0.89916) (xy 0 -0.9017)
						(xy 0.03175 -0.89916) (xy 0.0635 -0.889) (xy 0.09144 -0.87376) (xy 0.11684 -0.85344) (xy 0.13716 -0.82804)
						(xy 0.1524 -0.8001) (xy 0.16256 -0.76835) (xy 0.1651 -0.7366) (xy 0.1651 -0.44958) (xy 0.17272 -0.44196)
						(xy 0.19812 -0.4064) (xy 0.2032 -0.39624) (xy 0.20701 -0.38735) (xy 0.21209 -0.37719) (xy 0.2159 -0.36703)
						(xy 0.21844 -0.35687) (xy 0.22225 -0.34544) (xy 0.22352 -0.33528) (xy 0.22606 -0.32512) (xy 0.22733 -0.31369)
						(xy 0.22733 -0.30353) (xy 0.2286 -0.2921) (xy 0.22733 -0.28067) (xy 0.22733 -0.27051) (xy 0.22606 -0.25908)
						(xy 0.22352 -0.24892) (xy 0.22225 -0.23876) (xy 0.21844 -0.22733) (xy 0.2159 -0.21717) (xy 0.21209 -0.20701)
						(xy 0.20701 -0.19685) (xy 0.2032 -0.18796) (xy 0.19812 -0.1778) (xy 0.17272 -0.14224) (xy 0.1651 -0.13462)
						(xy 0.1651 0.7366) (xy 0.16256 0.76835) (xy 0.1524 0.8001) (xy 0.13716 0.82804) (xy 0.11684 0.85344)
						(xy 0.09144 0.87376) (xy 0.0635 0.889) (xy 0.03175 0.89916)
					)
					(width 0)
					(fill yes)
				)
			)
		)
		(pad "110" smd custom
			(at 3.450082 -4.106672 180)
			(size 0.1143 0.1143)
			(layers "F.Cu" "F.Mask" "F.Paste")
			(net "PV_VDDR")
			(options
				(clearance outline)
				(anchor circle)
			)
			(primitives
				(gr_poly
					(pts
						(xy 0 0.9017) (xy -0.03175 0.89916) (xy -0.0635 0.889) (xy -0.09144 0.87376) (xy -0.11684 0.85344)
						(xy -0.13716 0.82804) (xy -0.1524 0.8001) (xy -0.16256 0.76835) (xy -0.1651 0.7366) (xy -0.1651 0.44958)
						(xy -0.17272 0.44196) (xy -0.19812 0.4064) (xy -0.2032 0.39624) (xy -0.20701 0.38735) (xy -0.21209 0.37719)
						(xy -0.2159 0.36703) (xy -0.21844 0.35687) (xy -0.22225 0.34544) (xy -0.22352 0.33528) (xy -0.22606 0.32512)
						(xy -0.22733 0.31369) (xy -0.22733 0.30353) (xy -0.2286 0.2921) (xy -0.22733 0.28067) (xy -0.22733 0.27051)
						(xy -0.22606 0.25908) (xy -0.22352 0.24892) (xy -0.22225 0.23876) (xy -0.21844 0.22733) (xy -0.2159 0.21717)
						(xy -0.21209 0.20701) (xy -0.20701 0.19685) (xy -0.2032 0.18796) (xy -0.19812 0.1778) (xy -0.17272 0.14224)
						(xy -0.1651 0.13462) (xy -0.1651 -0.7366) (xy -0.16256 -0.76835) (xy -0.1524 -0.8001) (xy -0.13716 -0.82804)
						(xy -0.11684 -0.85344) (xy -0.09144 -0.87376) (xy -0.0635 -0.889) (xy -0.03175 -0.89916) (xy 0 -0.9017)
						(xy 0.03175 -0.89916) (xy 0.0635 -0.889) (xy 0.09144 -0.87376) (xy 0.11684 -0.85344) (xy 0.13716 -0.82804)
						(xy 0.1524 -0.8001) (xy 0.16256 -0.76835) (xy 0.1651 -0.7366) (xy 0.1651 0.13462) (xy 0.17272 0.14224)
						(xy 0.19812 0.1778) (xy 0.2032 0.18796) (xy 0.20701 0.19685) (xy 0.21209 0.20701) (xy 0.2159 0.21717)
						(xy 0.21844 0.22733) (xy 0.22225 0.23876) (xy 0.22352 0.24892) (xy 0.22606 0.25908) (xy 0.22733 0.27051)
						(xy 0.22733 0.28067) (xy 0.2286 0.2921) (xy 0.22733 0.30353) (xy 0.22733 0.31369) (xy 0.22606 0.32512)
						(xy 0.22352 0.33528) (xy 0.22225 0.34544) (xy 0.21844 0.35687) (xy 0.2159 0.36703) (xy 0.21209 0.37719)
						(xy 0.20701 0.38735) (xy 0.2032 0.39624) (xy 0.19812 0.4064) (xy 0.17272 0.44196) (xy 0.1651 0.44958)
						(xy 0.1651 0.7366) (xy 0.16256 0.76835) (xy 0.1524 0.8001) (xy 0.13716 0.82804) (xy 0.11684 0.85344)
						(xy 0.09144 0.87376) (xy 0.0635 0.889) (xy 0.03175 0.89916)
					)
					(width 0)
					(fill yes)
				)
			)
		)
		(pad "111" smd custom
			(at 3.750056 4.106672 180)
			(size 0.1143 0.1143)
			(layers "F.Cu" "F.Mask" "F.Paste")
			(net "M_A_CK_DP2")
			(options
				(clearance outline)
				(anchor circle)
			)
			(primitives
				(gr_poly
					(pts
						(xy 0 0.9017) (xy -0.03175 0.89916) (xy -0.0635 0.889) (xy -0.09144 0.87376) (xy -0.11684 0.85344)
						(xy -0.13716 0.82804) (xy -0.1524 0.8001) (xy -0.16256 0.76835) (xy -0.1651 0.7366) (xy -0.1651 0.11938)
						(xy -0.17272 0.11176) (xy -0.19812 0.0762) (xy -0.2032 0.06604) (xy -0.20701 0.05715) (xy -0.21209 0.04699)
						(xy -0.2159 0.03683) (xy -0.21844 0.02667) (xy -0.22225 0.01524) (xy -0.22352 0.00508) (xy -0.22606 -0.00508)
						(xy -0.22733 -0.01651) (xy -0.22733 -0.02667) (xy -0.2286 -0.0381) (xy -0.22733 -0.04953) (xy -0.22733 -0.05969)
						(xy -0.22606 -0.07112) (xy -0.22352 -0.08128) (xy -0.22225 -0.09144) (xy -0.21844 -0.10287) (xy -0.2159 -0.11303)
						(xy -0.21209 -0.12319) (xy -0.20701 -0.13335) (xy -0.2032 -0.14224) (xy -0.19812 -0.1524) (xy -0.17272 -0.18796)
						(xy -0.1651 -0.19558) (xy -0.1651 -0.7366) (xy -0.16256 -0.76835) (xy -0.1524 -0.8001) (xy -0.13716 -0.82804)
						(xy -0.11684 -0.85344) (xy -0.09144 -0.87376) (xy -0.0635 -0.889) (xy -0.03175 -0.89916) (xy 0 -0.9017)
						(xy 0.03175 -0.89916) (xy 0.0635 -0.889) (xy 0.09144 -0.87376) (xy 0.11684 -0.85344) (xy 0.13716 -0.82804)
						(xy 0.1524 -0.8001) (xy 0.16256 -0.76835) (xy 0.1651 -0.7366) (xy 0.1651 -0.19685) (xy 0.17272 -0.18923)
						(xy 0.17907 -0.18034) (xy 0.18669 -0.17145) (xy 0.19177 -0.16256) (xy 0.19812 -0.15367) (xy 0.20828 -0.13335)
						(xy 0.21971 -0.10287) (xy 0.22225 -0.09271) (xy 0.22479 -0.08128) (xy 0.22606 -0.07112) (xy 0.2286 -0.05969)
						(xy 0.2286 -0.01651) (xy 0.22606 -0.00508) (xy 0.22479 0.00508) (xy 0.22225 0.01651) (xy 0.21971 0.02667)
						(xy 0.20828 0.05715) (xy 0.19812 0.07747) (xy 0.19177 0.08636) (xy 0.18669 0.09525) (xy 0.17907 0.10414)
						(xy 0.17272 0.11303) (xy 0.1651 0.12065) (xy 0.1651 0.7366) (xy 0.16256 0.76835) (xy 0.1524 0.8001)
						(xy 0.13716 0.82804) (xy 0.11684 0.85344) (xy 0.09144 0.87376) (xy 0.0635 0.889) (xy 0.03175 0.89916)
					)
					(width 0)
					(fill yes)
				)
			)
		)
	)
)
